# BASEBOARD_FAB2 (Tioga Pass) — schematic netlist excerpt (pin names and nets, part order shuffled) for the footprints in the layout excerpt that follows; sources: Cadence DE-HDL packaged netlist, KiCad conversion of Wiwynn_Tioga_Pass_MB.brd

R7D29  RES  33.2 1% CHIP  pkg 0402  page 92 : A = FM_CPU0_FIVR_FAULT_R_LVT3 ; B = FM_CPU0_FIVR_FAULT_LVT3
R1D29  RES  4.75K 1% CHIP  pkg 0402  page 199 : A = A_HSC_VCAP ; B = FM_P12V_HSC_ADR1
C8E14  CAP  1.0UF 16V 10% X6S  pkg 0402  page 240 : A = VR_FET_SW_P12V_STBY_P3V3_STBY ; B = GND

(kicad_pcb
	(version 20260206)
	(generator "pcbnew")
	(generator_version "10.0")
	(general
		(thickness 1.6)
		(legacy_teardrops no)
	)
	(paper "A4")
	(title_block
		(title "Wiwynn_Tioga_Pass_MB.brd")
		(comment 1 "Tioga Pass / footprints 2242-2244 of 4770")
	)
	(layers
		(0 "F.Cu" signal "TOP")
		(4 "In1.Cu" signal "L2GND")
		(6 "In2.Cu" signal "L3")
		(8 "In3.Cu" signal "L4GND")
		(10 "In4.Cu" signal "L5")
		(12 "In5.Cu" signal "L6GND")
		(14 "In6.Cu" signal "L7VCC")
		(16 "In7.Cu" signal "L8VCC")
		(18 "In8.Cu" signal "L9GND")
		(20 "In9.Cu" signal "L10")
		(22 "In10.Cu" signal "L11GND")
		(24 "In11.Cu" signal "L12")
		(26 "In12.Cu" signal "L13GND")
		(2 "B.Cu" signal "BOTTOM")
		(9 "F.Adhes" user "F.Adhesive")
		(11 "B.Adhes" user "B.Adhesive")
		(13 "F.Paste" user "Package Geometry/Pastemask Top")
		(15 "B.Paste" user "Package Geometry/Pastemask Bottom")
		(5 "F.SilkS" user "Ref Des/Silkscreen Top")
		(7 "B.SilkS" user "Ref Des/Silkscreen Bottom")
		(1 "F.Mask" user "Board Geometry/Soldermask Top")
		(3 "B.Mask" user "Board Geometry/Soldermask Bottom")
		(17 "Dwgs.User" user "User.Drawings")
		(19 "Cmts.User" user "User.Comments")
		(21 "Eco1.User" user "User.Eco1")
		(23 "Eco2.User" user "User.Eco2")
		(25 "Edge.Cuts" user "Board Geometry/Outline")
		(27 "Margin" user)
		(31 "F.CrtYd" user "Package Geometry/Place Bound Top")
		(29 "B.CrtYd" user "Package Geometry/Place Bound Bottom")
		(35 "F.Fab" user "Ref Des/Assembly Top")
		(33 "B.Fab" user "Ref Des/Assembly Bottom")
	)
	(footprint ""
		(layer "F.Cu")
		(at 23.114 -78.613 -90)
		(property "Reference" "R1D29"
			(at 0 0 270)
			(layer "F.SilkS")
			(hide yes)
			(effects
				(font
					(size 1.27 1.27)
				)
			)
		)
		(property "Value" ""
			(at 0 0 270)
			(layer "F.Fab")
			(effects
				(font
					(size 1.27 1.27)
				)
			)
		)
		(duplicate_pad_numbers_are_jumpers no)
		(fp_rect
			(start -0.2794 -0.1016)
			(end 0.2794 0.9906)
			(stroke
				(width 0)
				(type default)
			)
			(fill no)
			(layer "F.CrtYd")
		)
		(fp_line
			(start -0.2794 0.9906)
			(end 0.2794 0.9906)
			(stroke
				(width 0.1)
				(type default)
			)
			(layer "F.Fab")
		)
		(fp_line
			(start 0.2794 0.9906)
			(end 0.2794 -0.1016)
			(stroke
				(width 0.1)
				(type default)
			)
			(layer "F.Fab")
		)
		(fp_line
			(start -0.2794 -0.1016)
			(end -0.2794 0.9906)
			(stroke
				(width 0.1)
				(type default)
			)
			(layer "F.Fab")
		)
		(fp_line
			(start 0.2794 -0.1016)
			(end -0.2794 -0.1016)
			(stroke
				(width 0.1)
				(type default)
			)
			(layer "F.Fab")
		)
		(pad "1" smd rect
			(at 0 0 270)
			(size 0.508 0.508)
			(layers "F.Cu" "F.Mask" "F.Paste")
			(net "A_HSC_VCAP")
		)
		(pad "2" smd rect
			(at 0 0.889 270)
			(size 0.508 0.508)
			(layers "F.Cu" "F.Mask" "F.Paste")
			(net "FM_P12V_HSC_ADR1")
		)
		(zone
			(layer "F.Cu")
			(hatch none 0.5)
			(connect_pads
				(clearance 0)
			)
			(min_thickness 0.25)
			(keepout
				(tracks allowed)
				(vias not_allowed)
				(pads allowed)
				(copperpour not_allowed)
				(footprints allowed)
			)
			(placement
				(enabled no)
				(sheetname "")
			)
			(fill
				(thermal_gap 0.5)
				(thermal_bridge_width 0.5)
				(island_removal_mode 0)
			)
			(polygon
				(pts
					(xy 22.86 -78.867) (xy 22.479 -78.867) (xy 22.479 -78.359) (xy 22.86 -78.359)
				)
			)
		)
		(zone
			(layer "F.Cu")
			(hatch none 0.5)
			(connect_pads
				(clearance 0)
			)
			(min_thickness 0.25)
			(keepout
				(tracks not_allowed)
				(vias allowed)
				(pads allowed)
				(copperpour not_allowed)
				(footprints allowed)
			)
			(placement
				(enabled no)
				(sheetname "")
			)
			(fill
				(thermal_gap 0.5)
				(thermal_bridge_width 0.5)
				(island_removal_mode 0)
			)
			(polygon
				(pts
					(xy 22.86 -78.867) (xy 22.479 -78.867) (xy 22.479 -78.359) (xy 22.86 -78.359)
				)
			)
		)
	)
	(footprint ""
		(layer "F.Cu")
		(at 394.6525 -77.597 90)
		(property "Reference" "R7D29"
			(at 0 0 90)
			(layer "F.SilkS")
			(hide yes)
			(effects
				(font
					(size 1.27 1.27)
				)
			)
		)
		(property "Value" ""
			(at 0 0 90)
			(layer "F.Fab")
			(effects
				(font
					(size 1.27 1.27)
				)
			)
		)
		(duplicate_pad_numbers_are_jumpers no)
		(fp_poly
			(pts
				(xy -0.2794 -0.1016) (xy 0.2794 -0.1016) (xy 0.2794 0.9906) (xy -0.2794 0.9906)
			)
			(stroke
				(width 0)
				(type default)
			)
			(fill no)
			(layer "F.CrtYd")
		)
		(fp_line
			(start 0.2794 -0.1016)
			(end -0.2794 -0.1016)
			(stroke
				(width 0.1)
				(type default)
			)
			(layer "F.Fab")
		)
		(fp_line
			(start -0.2794 -0.1016)
			(end -0.2794 0.9906)
			(stroke
				(width 0.1)
				(type default)
			)
			(layer "F.Fab")
		)
		(fp_line
			(start 0.2794 0.9906)
			(end 0.2794 -0.1016)
			(stroke
				(width 0.1)
				(type default)
			)
			(layer "F.Fab")
		)
		(fp_line
			(start -0.2794 0.9906)
			(end 0.2794 0.9906)
			(stroke
				(width 0.1)
				(type default)
			)
			(layer "F.Fab")
		)
		(pad "1" smd rect
			(at 0 0 90)
			(size 0.508 0.508)
			(layers "F.Cu" "F.Mask" "F.Paste")
			(net "FM_CPU0_FIVR_FAULT_R_LVT3")
		)
		(pad "2" smd rect
			(at 0 0.889 90)
			(size 0.508 0.508)
			(layers "F.Cu" "F.Mask" "F.Paste")
			(net "FM_CPU0_FIVR_FAULT_LVT3")
		)
		(zone
			(layer "F.Cu")
			(hatch none 0.5)
			(connect_pads
				(clearance 0)
			)
			(min_thickness 0.25)
			(keepout
				(tracks allowed)
				(vias not_allowed)
				(pads allowed)
				(copperpour not_allowed)
				(footprints allowed)
			)
			(placement
				(enabled no)
				(sheetname "")
			)
			(fill
				(thermal_gap 0.5)
				(thermal_bridge_width 0.5)
				(island_removal_mode 0)
			)
			(polygon
				(pts
					(xy 394.9065 -77.343) (xy 394.9065 -77.851) (xy 395.2875 -77.851) (xy 395.2875 -77.343)
				)
			)
		)
		(zone
			(layer "F.Cu")
			(hatch none 0.5)
			(connect_pads
				(clearance 0)
			)
			(min_thickness 0.25)
			(keepout
				(tracks not_allowed)
				(vias allowed)
				(pads allowed)
				(copperpour not_allowed)
				(footprints allowed)
			)
			(placement
				(enabled no)
				(sheetname "")
			)
			(fill
				(thermal_gap 0.5)
				(thermal_bridge_width 0.5)
				(island_removal_mode 0)
			)
			(polygon
				(pts
					(xy 395.2875 -77.343) (xy 395.2875 -77.851) (xy 394.9065 -77.851) (xy 394.9065 -77.343)
				)
			)
		)
	)
	(footprint ""
		(layer "F.Cu")
		(at 471.507566 -26.299668 180)
		(property "Reference" "C8E14"
			(at 0 0 180)
			(layer "F.SilkS")
			(hide yes)
			(effects
				(font
					(size 1.27 1.27)
				)
			)
		)
		(property "Value" ""
			(at 0 0 180)
			(layer "F.Fab")
			(effects
				(font
					(size 1.27 1.27)
				)
			)
		)
		(duplicate_pad_numbers_are_jumpers no)
		(fp_poly
			(pts
				(xy 0.3048 -0.1016) (xy 0.3048 0.9906) (xy -0.3048 0.9906) (xy -0.3048 -0.1016)
			)
			(stroke
				(width 0)
				(type default)
			)
			(fill no)
			(layer "F.CrtYd")
		)
		(fp_line
			(start 0.3048 0.9906)
			(end 0.3048 -0.1016)
			(stroke
				(width 0.1)
				(type default)
			)
			(layer "F.Fab")
		)
		(fp_line
			(start 0.3048 -0.1016)
			(end -0.3048 -0.1016)
			(stroke
				(width 0.1)
				(type default)
			)
			(layer "F.Fab")
		)
		(fp_line
			(start -0.3048 0.9906)
			(end 0.3048 0.9906)
			(stroke
				(width 0.1)
				(type default)
			)
			(layer "F.Fab")
		)
		(fp_line
			(start -0.3048 -0.1016)
			(end -0.3048 0.9906)
			(stroke
				(width 0.1)
				(type default)
			)
			(layer "F.Fab")
		)
		(pad "1" smd rect
			(at 0 0 180)
			(size 0.508 0.508)
			(layers "F.Cu" "F.Mask" "F.Paste")
			(net "VR_FET_SW_P12V_STBY_P3V3_STBY")
		)
		(pad "2" smd rect
			(at 0 0.889 180)
			(size 0.508 0.508)
			(layers "F.Cu" "F.Mask" "F.Paste")
			(net "GND")
		)
		(zone
			(layer "F.Cu")
			(hatch none 0.5)
			(connect_pads
				(clearance 0)
			)
			(min_thickness 0.25)
			(keepout
				(tracks not_allowed)
				(vias allowed)
				(pads allowed)
				(copperpour not_allowed)
				(footprints allowed)
			)
			(placement
				(enabled no)
				(sheetname "")
			)
			(fill
				(thermal_gap 0.5)
				(thermal_bridge_width 0.5)
				(island_removal_mode 0)
			)
			(polygon
				(pts
					(xy 471.761566 -26.934668) (xy 471.253566 -26.934668) (xy 471.253566 -26.553668) (xy 471.761566 -26.553668)
				)
			)
		)
		(zone
			(layer "F.Cu")
			(hatch none 0.5)
			(connect_pads
				(clearance 0)
			)
			(min_thickness 0.25)
			(keepout
				(tracks allowed)
				(vias not_allowed)
				(pads allowed)
				(copperpour not_allowed)
				(footprints allowed)
			)
			(placement
				(enabled no)
				(sheetname "")
			)
			(fill
				(thermal_gap 0.5)
				(thermal_bridge_width 0.5)
				(island_removal_mode 0)
			)
			(polygon
				(pts
					(xy 471.761566 -26.553668) (xy 471.253566 -26.553668) (xy 471.253566 -26.934668) (xy 471.761566 -26.934668)
				)
			)
		)
	)
)
